(kicad_pcb
	(version 20260206)
	(generator "pcbnew")
	(generator_version "10.0")
	(general
		(thickness 1.6)
		(legacy_teardrops no)
	)
	(paper "A4")
	(title_block
		(title "Bryce Canyon_SCC_16316-1_OCP.brd")
		(comment 1 "Bryce Canyon / footprints 617-624 of 1561")
	)
	(layers
		(0 "F.Cu" signal "TOP")
		(4 "In1.Cu" signal "L2GND")
		(6 "In2.Cu" signal "L3")
		(8 "In3.Cu" signal "L4VCC")
		(10 "In4.Cu" signal "L5VCC")
		(12 "In5.Cu" signal "L6")
		(14 "In6.Cu" signal "L7GND")
		(2 "B.Cu" signal "BOTTOM")
		(9 "F.Adhes" user "F.Adhesive")
		(11 "B.Adhes" user "B.Adhesive")
		(13 "F.Paste" user "Package Geometry/Pastemask Top")
		(15 "B.Paste" user "Package Geometry/Pastemask Bottom")
		(5 "F.SilkS" user "Ref Des/Silkscreen Top")
		(7 "B.SilkS" user "Ref Des/Silkscreen Bottom")
		(1 "F.Mask" user "Board Geometry/Soldermask Top")
		(3 "B.Mask" user "Board Geometry/Soldermask Bottom")
		(17 "Dwgs.User" user "User.Drawings")
		(19 "Cmts.User" user "User.Comments")
		(21 "Eco1.User" user "User.Eco1")
		(23 "Eco2.User" user "User.Eco2")
		(25 "Edge.Cuts" user "Board Geometry/Outline")
		(27 "Margin" user)
		(31 "F.CrtYd" user "Package Geometry/Place Bound Top")
		(29 "B.CrtYd" user "Package Geometry/Place Bound Bottom")
		(35 "F.Fab" user "Ref Des/Assembly Top")
		(33 "B.Fab" user "Ref Des/Assembly Bottom")
	)
	(footprint ""
		(layer "F.Cu")
		(at 180.3908 -110.80242)
		(property "Reference" "R604"
			(at 0 0 0)
			(layer "F.SilkS")
			(hide yes)
			(effects
				(font
					(size 1.27 1.27)
				)
			)
		)
		(property "Value" "4K7R2F-GP"
			(at 0.064008 -3.993896 0)
			(unlocked yes)
			(layer "F.Fab")
			(hide yes)
			(effects
				(font
					(size 1.016 1.016)
					(thickness 0.1524)
				)
			)
		)
		(property "Device Type" "R402H16"
			(at 0.064008 -5.517896 0)
			(unlocked yes)
			(layer "F.Fab")
			(hide yes)
			(effects
				(font
					(size 1.016 1.016)
					(thickness 0.1524)
				)
			)
		)
		(duplicate_pad_numbers_are_jumpers no)
		(fp_line
			(start -0.508 -0.9398)
			(end -0.508 0.9398)
			(stroke
				(width 0.1524)
				(type default)
			)
			(layer "F.SilkS")
		)
		(fp_line
			(start 0.508 -0.9398)
			(end -0.508 -0.9398)
			(stroke
				(width 0.1524)
				(type default)
			)
			(layer "F.SilkS")
		)
		(fp_rect
			(start -0.508 0.9398)
			(end 0.508 -0.9398)
			(stroke
				(width 0)
				(type default)
			)
			(fill no)
			(layer "F.CrtYd")
		)
		(fp_rect
			(start -0.508 0.9398)
			(end 0.508 -0.9398)
			(stroke
				(width 0)
				(type default)
			)
			(fill no)
			(layer "F.Fab")
		)
		(pad "1" smd custom
			(at 0 -0.4445)
			(size 0.1397 0.1397)
			(layers "F.Cu" "F.Mask" "F.Paste")
			(net "P3V3")
			(options
				(clearance outline)
				(anchor circle)
			)
			(primitives
				(gr_poly
					(pts
						(arc
							(start -0.1778 -0.2794)
							(mid -0.249642 -0.249642)
							(end -0.2794 -0.1778)
						)
						(arc
							(start -0.2794 0.1778)
							(mid -0.249642 0.249642)
							(end -0.1778 0.2794)
						)
						(arc
							(start 0.1778 0.2794)
							(mid 0.249642 0.249642)
							(end 0.2794 0.1778)
						)
						(arc
							(start 0.2794 -0.1778)
							(mid 0.249642 -0.249642)
							(end 0.1778 -0.2794)
						)
					)
					(width 0)
					(fill yes)
				)
			)
		)
		(pad "2" smd custom
			(at 0 0.4445)
			(size 0.1397 0.1397)
			(layers "F.Cu" "F.Mask" "F.Paste")
			(net "P1V8_C_PG_R_1")
			(options
				(clearance outline)
				(anchor circle)
			)
			(primitives
				(gr_poly
					(pts
						(arc
							(start -0.1778 -0.2794)
							(mid -0.249642 -0.249642)
							(end -0.2794 -0.1778)
						)
						(arc
							(start -0.2794 0.1778)
							(mid -0.249642 0.249642)
							(end -0.1778 0.2794)
						)
						(arc
							(start 0.1778 0.2794)
							(mid 0.249642 0.249642)
							(end 0.2794 0.1778)
						)
						(arc
							(start 0.2794 -0.1778)
							(mid 0.249642 -0.249642)
							(end 0.1778 -0.2794)
						)
					)
					(width 0)
					(fill yes)
				)
			)
		)
	)
	(footprint ""
		(layer "F.Cu")
		(at 139.072112 -80.197452 180)
		(property "Reference" "VIA27"
			(at 0 0 180)
			(layer "F.SilkS")
			(hide yes)
			(effects
				(font
					(size 1.27 1.27)
				)
			)
		)
		(property "Value" "100OHM-8L-1D6MM-L18L16-GP"
			(at -3.7211 -4.5085 180)
			(unlocked yes)
			(layer "F.Fab")
			(hide yes)
			(effects
				(font
					(size 1.016 1.016)
					(thickness 0.1524)
				)
			)
		)
		(property "Device Type" "VIA-PCIE-4P-394076"
			(at -3.7211 -6.0325 180)
			(unlocked yes)
			(layer "F.Fab")
			(hide yes)
			(effects
				(font
					(size 1.016 1.016)
					(thickness 0.1524)
				)
			)
		)
		(duplicate_pad_numbers_are_jumpers no)
		(fp_rect
			(start -1.9685 0.381)
			(end 1.9685 -0.381)
			(stroke
				(width 0)
				(type default)
			)
			(fill no)
			(layer "F.CrtYd")
		)
		(fp_rect
			(start -1.9685 0.381)
			(end 1.9685 -0.381)
			(stroke
				(width 0)
				(type default)
			)
			(fill no)
			(layer "F.Fab")
		)
		(pad "1" thru_hole circle
			(at -1.5875 0 180)
			(size 0.508 0.508)
			(drill 0.254)
			(layers "*.Cu" "*.Mask")
			(remove_unused_layers no)
			(net "GND")
			(clearance 0.127)
			(thermal_gap 0.127)
		)
		(pad "2" thru_hole circle
			(at -0.5715 0 180)
			(size 0.508 0.508)
			(drill 0.254)
			(layers "*.Cu" "*.Mask")
			(remove_unused_layers no)
			(net "PHY_EXP_TO_CONN_10_DP")
			(clearance 0.127)
			(thermal_gap 0.127)
		)
		(pad "3" thru_hole circle
			(at 0.5715 0 180)
			(size 0.508 0.508)
			(drill 0.254)
			(layers "*.Cu" "*.Mask")
			(remove_unused_layers no)
			(net "PHY_EXP_TO_CONN_10_DN")
			(clearance 0.127)
			(thermal_gap 0.127)
		)
		(pad "4" thru_hole circle
			(at 1.5875 0 180)
			(size 0.508 0.508)
			(drill 0.254)
			(layers "*.Cu" "*.Mask")
			(remove_unused_layers no)
			(net "GND")
			(clearance 0.127)
			(thermal_gap 0.127)
		)
	)
	(footprint ""
		(layer "F.Cu")
		(at 198.8312 -82.92338 180)
		(property "Reference" "R442"
			(at 0 0 180)
			(layer "F.SilkS")
			(hide yes)
			(effects
				(font
					(size 1.27 1.27)
				)
			)
		)
		(property "Value" "0R2J-2-GP"
			(at 0.064008 -3.993896 180)
			(unlocked yes)
			(layer "F.Fab")
			(hide yes)
			(effects
				(font
					(size 1.016 1.016)
					(thickness 0.1524)
				)
			)
		)
		(property "Device Type" "R402H16"
			(at 0.064008 -5.517896 180)
			(unlocked yes)
			(layer "F.Fab")
			(hide yes)
			(effects
				(font
					(size 1.016 1.016)
					(thickness 0.1524)
				)
			)
		)
		(duplicate_pad_numbers_are_jumpers no)
		(fp_line
			(start 0.508 -0.9398)
			(end -0.508 -0.9398)
			(stroke
				(width 0.1524)
				(type default)
			)
			(layer "F.SilkS")
		)
		(fp_line
			(start -0.508 -0.9398)
			(end -0.508 0.9398)
			(stroke
				(width 0.1524)
				(type default)
			)
			(layer "F.SilkS")
		)
		(fp_rect
			(start -0.508 0.9398)
			(end 0.508 -0.9398)
			(stroke
				(width 0)
				(type default)
			)
			(fill no)
			(layer "F.CrtYd")
		)
		(fp_rect
			(start -0.508 0.9398)
			(end 0.508 -0.9398)
			(stroke
				(width 0)
				(type default)
			)
			(fill no)
			(layer "F.Fab")
		)
		(pad "1" smd custom
			(at 0 -0.4445 180)
			(size 0.1397 0.1397)
			(layers "F.Cu" "F.Mask" "F.Paste")
			(net "P5V")
			(options
				(clearance outline)
				(anchor circle)
			)
			(primitives
				(gr_poly
					(pts
						(arc
							(start -0.1778 -0.2794)
							(mid -0.249642 -0.249642)
							(end -0.2794 -0.1778)
						)
						(arc
							(start -0.2794 0.1778)
							(mid -0.249642 0.249642)
							(end -0.1778 0.2794)
						)
						(arc
							(start 0.1778 0.2794)
							(mid 0.249642 0.249642)
							(end 0.2794 0.1778)
						)
						(arc
							(start 0.2794 -0.1778)
							(mid 0.249642 -0.249642)
							(end 0.1778 -0.2794)
						)
					)
					(width 0)
					(fill yes)
				)
			)
		)
		(pad "2" smd custom
			(at 0 0.4445 180)
			(size 0.1397 0.1397)
			(layers "F.Cu" "F.Mask" "F.Paste")
			(net "SDB_CONN_PWR_3")
			(options
				(clearance outline)
				(anchor circle)
			)
			(primitives
				(gr_poly
					(pts
						(arc
							(start -0.1778 -0.2794)
							(mid -0.249642 -0.249642)
							(end -0.2794 -0.1778)
						)
						(arc
							(start -0.2794 0.1778)
							(mid -0.249642 0.249642)
							(end -0.1778 0.2794)
						)
						(arc
							(start 0.1778 0.2794)
							(mid 0.249642 0.249642)
							(end 0.2794 0.1778)
						)
						(arc
							(start 0.2794 -0.1778)
							(mid 0.249642 -0.249642)
							(end 0.1778 -0.2794)
						)
					)
					(width 0)
					(fill yes)
				)
			)
		)
	)
	(footprint ""
		(layer "F.Cu")
		(at 162.405568 -22.462744 180)
		(property "Reference" "R169"
			(at 0 0 180)
			(layer "F.SilkS")
			(hide yes)
			(effects
				(font
					(size 1.27 1.27)
				)
			)
		)
		(property "Value" "0R2J-2-GP"
			(at 0.064008 -3.993896 180)
			(unlocked yes)
			(layer "F.Fab")
			(hide yes)
			(effects
				(font
					(size 1.016 1.016)
					(thickness 0.1524)
				)
			)
		)
		(property "Device Type" "R402H16"
			(at 0.064008 -5.517896 180)
			(unlocked yes)
			(layer "F.Fab")
			(hide yes)
			(effects
				(font
					(size 1.016 1.016)
					(thickness 0.1524)
				)
			)
		)
		(duplicate_pad_numbers_are_jumpers no)
		(fp_line
			(start 0.508 -0.9398)
			(end -0.508 -0.9398)
			(stroke
				(width 0.1524)
				(type default)
			)
			(layer "F.SilkS")
		)
		(fp_line
			(start -0.508 -0.9398)
			(end -0.508 0.9398)
			(stroke
				(width 0.1524)
				(type default)
			)
			(layer "F.SilkS")
		)
		(fp_rect
			(start -0.508 0.9398)
			(end 0.508 -0.9398)
			(stroke
				(width 0)
				(type default)
			)
			(fill no)
			(layer "F.CrtYd")
		)
		(fp_rect
			(start -0.508 0.9398)
			(end 0.508 -0.9398)
			(stroke
				(width 0)
				(type default)
			)
			(fill no)
			(layer "F.Fab")
		)
		(pad "1" smd custom
			(at 0 -0.4445 180)
			(size 0.1397 0.1397)
			(layers "F.Cu" "F.Mask" "F.Paste")
			(net "PCIE_COMP_TO_SCC_CLK_0_DP")
			(options
				(clearance outline)
				(anchor circle)
			)
			(primitives
				(gr_poly
					(pts
						(arc
							(start -0.1778 -0.2794)
							(mid -0.249642 -0.249642)
							(end -0.2794 -0.1778)
						)
						(arc
							(start -0.2794 0.1778)
							(mid -0.249642 0.249642)
							(end -0.1778 0.2794)
						)
						(arc
							(start 0.1778 0.2794)
							(mid 0.249642 0.249642)
							(end 0.2794 0.1778)
						)
						(arc
							(start 0.2794 -0.1778)
							(mid 0.249642 -0.249642)
							(end 0.1778 -0.2794)
						)
					)
					(width 0)
					(fill yes)
				)
			)
		)
		(pad "2" smd custom
			(at 0 0.4445 180)
			(size 0.1397 0.1397)
			(layers "F.Cu" "F.Mask" "F.Paste")
			(net "PCIE_CLK_R_P")
			(options
				(clearance outline)
				(anchor circle)
			)
			(primitives
				(gr_poly
					(pts
						(arc
							(start -0.1778 -0.2794)
							(mid -0.249642 -0.249642)
							(end -0.2794 -0.1778)
						)
						(arc
							(start -0.2794 0.1778)
							(mid -0.249642 0.249642)
							(end -0.1778 0.2794)
						)
						(arc
							(start 0.1778 0.2794)
							(mid 0.249642 0.249642)
							(end 0.2794 0.1778)
						)
						(arc
							(start 0.2794 -0.1778)
							(mid 0.249642 -0.249642)
							(end 0.1778 -0.2794)
						)
					)
					(width 0)
					(fill yes)
				)
			)
		)
	)
	(footprint ""
		(layer "F.Cu")
		(at 7.5438 -85.8012 -90)
		(property "Reference" "C545"
			(at 0 0 270)
			(layer "F.SilkS")
			(hide yes)
			(effects
				(font
					(size 1.27 1.27)
				)
			)
		)
		(property "Value" "SCD1U16V2KX-3GP"
			(at 1.1811 -2.7051 270)
			(unlocked yes)
			(layer "F.Fab")
			(hide yes)
			(effects
				(font
					(size 1.016 1.016)
					(thickness 0.1524)
				)
			)
		)
		(property "Device Type" "C402H22"
			(at 1.1811 -4.2291 270)
			(unlocked yes)
			(layer "F.Fab")
			(hide yes)
			(effects
				(font
					(size 1.016 1.016)
					(thickness 0.1524)
				)
			)
		)
		(duplicate_pad_numbers_are_jumpers no)
		(fp_rect
			(start -0.4318 0.9525)
			(end 0.4318 -0.9525)
			(stroke
				(width 0)
				(type default)
			)
			(fill no)
			(layer "F.CrtYd")
		)
		(fp_rect
			(start -0.4318 0.9525)
			(end 0.4318 -0.9525)
			(stroke
				(width 0)
				(type default)
			)
			(fill no)
			(layer "F.Fab")
		)
		(pad "1" smd custom
			(at 0 -0.4445 270)
			(size 0.1524 0.1524)
			(layers "F.Cu" "F.Mask" "F.Paste")
			(net "P1V8_E")
			(options
				(clearance outline)
				(anchor circle)
			)
			(primitives
				(gr_poly
					(pts
						(arc
							(start 0.3048 -0.2032)
							(mid 0.275042 -0.275042)
							(end 0.2032 -0.3048)
						)
						(arc
							(start -0.2032 -0.3048)
							(mid -0.275042 -0.275042)
							(end -0.3048 -0.2032)
						)
						(arc
							(start -0.3048 0.2032)
							(mid -0.275042 0.275042)
							(end -0.2032 0.3048)
						)
						(arc
							(start 0.2032 0.3048)
							(mid 0.275042 0.275042)
							(end 0.3048 0.2032)
						)
					)
					(width 0)
					(fill yes)
				)
			)
		)
		(pad "2" smd custom
			(at 0 0.4445 270)
			(size 0.1524 0.1524)
			(layers "F.Cu" "F.Mask" "F.Paste")
			(net "GND")
			(options
				(clearance outline)
				(anchor circle)
			)
			(primitives
				(gr_poly
					(pts
						(arc
							(start 0.3048 -0.2032)
							(mid 0.275042 -0.275042)
							(end 0.2032 -0.3048)
						)
						(arc
							(start -0.2032 -0.3048)
							(mid -0.275042 -0.275042)
							(end -0.3048 -0.2032)
						)
						(arc
							(start -0.3048 0.2032)
							(mid -0.275042 0.275042)
							(end -0.2032 0.3048)
						)
						(arc
							(start 0.2032 0.3048)
							(mid 0.275042 0.275042)
							(end 0.3048 0.2032)
						)
					)
					(width 0)
					(fill yes)
				)
			)
		)
	)
	(footprint ""
		(layer "F.Cu")
		(at 186.370468 -113.631218 90)
		(property "Reference" "R3"
			(at 0 0 90)
			(layer "F.SilkS")
			(hide yes)
			(effects
				(font
					(size 1.27 1.27)
				)
			)
		)
		(property "Value" "10KR2F-2-GP"
			(at 0.064008 -3.993896 90)
			(unlocked yes)
			(layer "F.Fab")
			(hide yes)
			(effects
				(font
					(size 1.016 1.016)
					(thickness 0.1524)
				)
			)
		)
		(property "Device Type" "R402H16"
			(at 0.064008 -5.517896 90)
			(unlocked yes)
			(layer "F.Fab")
			(hide yes)
			(effects
				(font
					(size 1.016 1.016)
					(thickness 0.1524)
				)
			)
		)
		(duplicate_pad_numbers_are_jumpers no)
		(fp_line
			(start 0.508 -0.9398)
			(end -0.508 -0.9398)
			(stroke
				(width 0.1524)
				(type default)
			)
			(layer "F.SilkS")
		)
		(fp_line
			(start -0.508 -0.9398)
			(end -0.508 0.9398)
			(stroke
				(width 0.1524)
				(type default)
			)
			(layer "F.SilkS")
		)
		(fp_rect
			(start -0.508 0.9398)
			(end 0.508 -0.9398)
			(stroke
				(width 0)
				(type default)
			)
			(fill no)
			(layer "F.CrtYd")
		)
		(fp_rect
			(start -0.508 0.9398)
			(end 0.508 -0.9398)
			(stroke
				(width 0)
				(type default)
			)
			(fill no)
			(layer "F.Fab")
		)
		(pad "1" smd custom
			(at 0 -0.4445 90)
			(size 0.1397 0.1397)
			(layers "F.Cu" "F.Mask" "F.Paste")
			(net "P12V_STBY_SCC")
			(options
				(clearance outline)
				(anchor circle)
			)
			(primitives
				(gr_poly
					(pts
						(arc
							(start -0.1778 -0.2794)
							(mid -0.249642 -0.249642)
							(end -0.2794 -0.1778)
						)
						(arc
							(start -0.2794 0.1778)
							(mid -0.249642 0.249642)
							(end -0.1778 0.2794)
						)
						(arc
							(start 0.1778 0.2794)
							(mid 0.249642 0.249642)
							(end 0.2794 0.1778)
						)
						(arc
							(start 0.2794 -0.1778)
							(mid 0.249642 -0.249642)
							(end 0.1778 -0.2794)
						)
					)
					(width 0)
					(fill yes)
				)
			)
		)
		(pad "2" smd custom
			(at 0 0.4445 90)
			(size 0.1397 0.1397)
			(layers "F.Cu" "F.Mask" "F.Paste")
			(net "P1V8_C_G_PG")
			(options
				(clearance outline)
				(anchor circle)
			)
			(primitives
				(gr_poly
					(pts
						(arc
							(start -0.1778 -0.2794)
							(mid -0.249642 -0.249642)
							(end -0.2794 -0.1778)
						)
						(arc
							(start -0.2794 0.1778)
							(mid -0.249642 0.249642)
							(end -0.1778 0.2794)
						)
						(arc
							(start 0.1778 0.2794)
							(mid 0.249642 0.249642)
							(end 0.2794 0.1778)
						)
						(arc
							(start 0.2794 -0.1778)
							(mid 0.249642 -0.249642)
							(end 0.1778 -0.2794)
						)
					)
					(width 0)
					(fill yes)
				)
			)
		)
	)
	(footprint ""
		(layer "F.Cu")
		(at 6.7564 -70.4088 180)
		(property "Reference" "R361"
			(at 0 0 180)
			(layer "F.SilkS")
			(hide yes)
			(effects
				(font
					(size 1.27 1.27)
				)
			)
		)
		(property "Value" "4K7R2F-GP"
			(at 0.064008 -3.993896 180)
			(unlocked yes)
			(layer "F.Fab")
			(hide yes)
			(effects
				(font
					(size 1.016 1.016)
					(thickness 0.1524)
				)
			)
		)
		(property "Device Type" "R402H16"
			(at 0.064008 -5.517896 180)
			(unlocked yes)
			(layer "F.Fab")
			(hide yes)
			(effects
				(font
					(size 1.016 1.016)
					(thickness 0.1524)
				)
			)
		)
		(duplicate_pad_numbers_are_jumpers no)
		(fp_line
			(start 0.508 -0.9398)
			(end -0.508 -0.9398)
			(stroke
				(width 0.1524)
				(type default)
			)
			(layer "F.SilkS")
		)
		(fp_line
			(start -0.508 -0.9398)
			(end -0.508 0.9398)
			(stroke
				(width 0.1524)
				(type default)
			)
			(layer "F.SilkS")
		)
		(fp_rect
			(start -0.508 0.9398)
			(end 0.508 -0.9398)
			(stroke
				(width 0)
				(type default)
			)
			(fill no)
			(layer "F.CrtYd")
		)
		(fp_rect
			(start -0.508 0.9398)
			(end 0.508 -0.9398)
			(stroke
				(width 0)
				(type default)
			)
			(fill no)
			(layer "F.Fab")
		)
		(pad "1" smd custom
			(at 0 -0.4445 180)
			(size 0.1397 0.1397)
			(layers "F.Cu" "F.Mask" "F.Paste")
			(net "P3V3")
			(options
				(clearance outline)
				(anchor circle)
			)
			(primitives
				(gr_poly
					(pts
						(arc
							(start -0.1778 -0.2794)
							(mid -0.249642 -0.249642)
							(end -0.2794 -0.1778)
						)
						(arc
							(start -0.2794 0.1778)
							(mid -0.249642 0.249642)
							(end -0.1778 0.2794)
						)
						(arc
							(start 0.1778 0.2794)
							(mid 0.249642 0.249642)
							(end 0.2794 0.1778)
						)
						(arc
							(start 0.2794 -0.1778)
							(mid 0.249642 -0.249642)
							(end 0.1778 -0.2794)
						)
					)
					(width 0)
					(fill yes)
				)
			)
		)
		(pad "2" smd custom
			(at 0 0.4445 180)
			(size 0.1397 0.1397)
			(layers "F.Cu" "F.Mask" "F.Paste")
			(net "FRU_EEPROM_A2")
			(options
				(clearance outline)
				(anchor circle)
			)
			(primitives
				(gr_poly
					(pts
						(arc
							(start -0.1778 -0.2794)
							(mid -0.249642 -0.249642)
							(end -0.2794 -0.1778)
						)
						(arc
							(start -0.2794 0.1778)
							(mid -0.249642 0.249642)
							(end -0.1778 0.2794)
						)
						(arc
							(start 0.1778 0.2794)
							(mid 0.249642 0.249642)
							(end 0.2794 0.1778)
						)
						(arc
							(start 0.2794 -0.1778)
							(mid 0.249642 -0.249642)
							(end 0.1778 -0.2794)
						)
					)
					(width 0)
					(fill yes)
				)
			)
		)
	)
	(footprint ""
		(layer "F.Cu")
		(at 55.88 -121.539 -90)
		(property "Reference" "C704"
			(at 0 0 270)
			(layer "F.SilkS")
			(hide yes)
			(effects
				(font
					(size 1.27 1.27)
				)
			)
		)
		(property "Value" "SC10U6D3V5KX-4GP"
			(at -0.0762 -6.1214 270)
			(unlocked yes)
			(layer "F.Fab")
			(hide yes)
			(effects
				(font
					(size 1.016 1.016)
					(thickness 0.1524)
				)
			)
		)
		(property "Device Type" "C805H58"
			(at -0.0762 -8.1534 270)
			(unlocked yes)
			(layer "F.Fab")
			(hide yes)
			(effects
				(font
					(size 1.016 1.016)
					(thickness 0.1524)
				)
			)
		)
		(duplicate_pad_numbers_are_jumpers no)
		(fp_line
			(start 0.635 0)
			(end -0.635 0)
			(stroke
				(width 0.508)
				(type default)
			)
			(layer "F.SilkS")
		)
		(fp_rect
			(start -0.9652 1.778)
			(end 0.9652 -1.778)
			(stroke
				(width 0)
				(type default)
			)
			(fill no)
			(layer "F.CrtYd")
		)
		(fp_poly
			(pts
				(xy -0.9652 -1.778) (xy 0.9652 -1.778) (xy 0.9652 1.778) (xy -0.9652 1.778)
			)
			(stroke
				(width 0)
				(type default)
			)
			(fill no)
			(layer "F.Fab")
		)
		(pad "1" smd rect
			(at 0 -0.9652 270)
			(size 1.397 1.143)
			(layers "F.Cu" "F.Mask" "F.Paste")
			(net "P3V3_OUT")
		)
		(pad "2" smd rect
			(at 0 0.9652 270)
			(size 1.397 1.143)
			(layers "F.Cu" "F.Mask" "F.Paste")
			(net "GND")
		)
	)
)
